(kicad_pcb
	(version 20241229)
	(generator "pcbnew")
	(generator_version "9.0")
	(general
		(thickness 1.599998)
		(legacy_teardrops no)
	)
	(paper "A4")
	(title_block
		(date "2023-02-12")
		(rev "1.1.5")
		(comment 9 "footprints 191-195 of 473")
	)
	(layers
		(0 "F.Cu" signal)
		(4 "In1.Cu" power "In1.GND")
		(6 "In2.Cu" signal)
		(8 "In3.Cu" power "In3.GND")
		(10 "In4.Cu" power "In4.VCC")
		(12 "In5.Cu" signal)
		(14 "In6.Cu" power "In6.VCC")
		(2 "B.Cu" signal)
		(9 "F.Adhes" user "F.Adhesive")
		(11 "B.Adhes" user "B.Adhesive")
		(13 "F.Paste" user)
		(15 "B.Paste" user)
		(5 "F.SilkS" user "F.Silkscreen")
		(7 "B.SilkS" user "B.Silkscreen")
		(1 "F.Mask" user)
		(3 "B.Mask" user)
		(17 "Dwgs.User" user "User.Drawings")
		(19 "Cmts.User" user "User.Comments")
		(21 "Eco1.User" user "User.Eco1")
		(23 "Eco2.User" user "User.Eco2")
		(25 "Edge.Cuts" user)
		(27 "Margin" user)
		(31 "F.CrtYd" user "F.Courtyard")
		(29 "B.CrtYd" user "B.Courtyard")
		(35 "F.Fab" user)
		(33 "B.Fab" user)
	)
	(footprint "antmicro-footprints:V-QFN2030-12"
		(layer "F.Cu")
		(at 114.611478 88.903992 180)
		(property "Reference" "U9"
			(at -0.888522 -2.296008 180)
			(layer "F.SilkS")
			(effects
				(font
					(size 0.7 0.7)
					(thickness 0.15)
				)
				(justify left bottom)
			)
		)
		(property "Value" "AP62600SJ-7"
			(at -4 2.2 180)
			(layer "F.Fab")
			(effects
				(font
					(size 0.7 0.7)
					(thickness 0.15)
				)
				(justify left bottom)
			)
		)
		(property "Description" "Buck Switching Regulator IC Positive Fixed 0.6V 1 Output 6A 12-VFQFN"
			(at 0 0 180)
			(layer "F.Fab")
			(hide yes)
			(effects
				(font
					(size 1.27 1.27)
					(thickness 0.15)
				)
			)
		)
		(property "Author" "Antmicro"
			(at 229.222956 177.807984 0)
			(layer "F.Fab")
			(hide yes)
			(effects
				(font
					(size 1 1)
					(thickness 0.15)
				)
			)
		)
		(property "License" "Apache-2.0"
			(at 229.222956 177.807984 0)
			(layer "F.Fab")
			(hide yes)
			(effects
				(font
					(size 1 1)
					(thickness 0.15)
				)
			)
		)
		(property "MPN" "AP62600SJ-7"
			(at 229.222956 177.807984 0)
			(layer "F.Fab")
			(hide yes)
			(effects
				(font
					(size 1 1)
					(thickness 0.15)
				)
			)
		)
		(property "Manufacturer" "Diodes Incorporated"
			(at 229.222956 177.807984 0)
			(layer "F.Fab")
			(hide yes)
			(effects
				(font
					(size 1 1)
					(thickness 0.15)
				)
			)
		)
		(sheetname "Supply")
		(sheetfile "supply.kicad_sch")
		(attr smd)
		(fp_line
			(start 1.8 1.199)
			(end 0.8 1.199)
			(stroke
				(width 0.15)
				(type solid)
			)
			(layer "F.SilkS")
		)
		(fp_line
			(start 1.8 0.998)
			(end 1.8 1.199)
			(stroke
				(width 0.15)
				(type solid)
			)
			(layer "F.SilkS")
		)
		(fp_line
			(start 1.8 -1.276)
			(end 1.8 -1.025)
			(stroke
				(width 0.15)
				(type solid)
			)
			(layer "F.SilkS")
		)
		(fp_line
			(start -0.802 1.199)
			(end -1.801 1.199)
			(stroke
				(width 0.15)
				(type solid)
			)
			(layer "F.SilkS")
		)
		(fp_line
			(start -1.801 1.199)
			(end -1.801 0.998)
			(stroke
				(width 0.15)
				(type solid)
			)
			(layer "F.SilkS")
		)
		(fp_line
			(start -1.801 -1)
			(end -1.801 -1.2)
			(stroke
				(width 0.15)
				(type solid)
			)
			(layer "F.SilkS")
		)
		(fp_line
			(start -1.801 -1.2)
			(end -0.802 -1.2)
			(stroke
				(width 0.15)
				(type solid)
			)
			(layer "F.SilkS")
		)
		(fp_circle
			(center 0.497 -1.7)
			(end 0.548 -1.7)
			(stroke
				(width 0.15)
				(type solid)
			)
			(fill yes)
			(layer "F.SilkS")
		)
		(fp_rect
			(start -2.026 -1.525)
			(end 2.023 1.524)
			(stroke
				(width 0.05)
				(type solid)
			)
			(fill no)
			(layer "F.CrtYd")
		)
		(fp_line
			(start 1.3 -1)
			(end 1.5 -0.8)
			(stroke
				(width 0.15)
				(type solid)
			)
			(layer "F.Fab")
		)
		(fp_rect
			(start -1.526 -1.025)
			(end 1.523 1.024)
			(stroke
				(width 0.15)
				(type solid)
			)
			(fill no)
			(layer "F.Fab")
		)
		(pad "1" smd rect
			(at 0.498 -0.552 90)
			(size 1.6 0.35)
			(layers "F.Cu" "F.Mask" "F.Paste")
			(net 5 "GND")
			(pinfunction "PGND")
			(pintype "passive")
		)
		(pad "2" smd rect
			(at -0.5 -0.552 90)
			(size 1.6 0.35)
			(layers "F.Cu" "F.Mask" "F.Paste")
			(net 463 "VCC5V0_INT")
			(pinfunction "VIN")
			(pintype "power_in")
		)
		(pad "3" smd rect
			(at -1.45 -0.75 90)
			(size 0.35 0.8)
			(layers "F.Cu" "F.Mask" "F.Paste")
			(net 594 "/Supply/1V8_EN")
			(pinfunction "EN")
			(pintype "input")
		)
		(pad "4" smd rect
			(at -1.45 -0.25 90)
			(size 0.35 0.8)
			(layers "F.Cu" "F.Mask" "F.Paste")
			(net 619 "/Supply/1V8_MODE")
			(pinfunction "MODE")
			(pintype "input")
		)
		(pad "5" smd rect
			(at -1.45 0.248 90)
			(size 0.35 0.8)
			(layers "F.Cu" "F.Mask" "F.Paste")
			(net 614 "/Supply/1V8_FSEL")
			(pinfunction "FSEL")
			(pintype "input")
		)
		(pad "6" smd rect
			(at -1.45 0.748 90)
			(size 0.35 0.8)
			(layers "F.Cu" "F.Mask" "F.Paste")
			(net 605 "/Supply/1V8_PG")
			(pinfunction "PG")
			(pintype "open_collector")
		)
		(pad "7" smd rect
			(at -0.5 0.949 180)
			(size 0.35 0.8)
			(layers "F.Cu" "F.Mask" "F.Paste")
			(net 552 "/Supply/1V8_BST")
			(pinfunction "BST")
			(pintype "input")
		)
		(pad "8" smd rect
			(at 0 0.55 90)
			(size 1.6 0.35)
			(layers "F.Cu" "F.Mask" "F.Paste")
			(net 584 "/Supply/1V8_SW")
			(pinfunction "SW")
			(pintype "output")
		)
		(pad "9" smd rect
			(at 1.449 0.748 270)
			(size 0.35 0.8)
			(layers "F.Cu" "F.Mask" "F.Paste")
			(net 595 "/Supply/1V8_VCC_INT")
			(pinfunction "VCC")
			(pintype "input")
		)
		(pad "10" smd rect
			(at 1.449 0.248 270)
			(size 0.35 0.8)
			(layers "F.Cu" "F.Mask" "F.Paste")
			(net 620 "/Supply/1V8_SS{slash}TR")
			(pinfunction "SS/TR")
			(pintype "input")
		)
		(pad "11" smd rect
			(at 1.449 -0.25 270)
			(size 0.35 0.8)
			(layers "F.Cu" "F.Mask" "F.Paste")
			(net 5 "GND")
			(pinfunction "GND")
			(pintype "passive")
		)
		(pad "12" smd rect
			(at 1.449 -0.75 270)
			(size 0.35 0.8)
			(layers "F.Cu" "F.Mask" "F.Paste")
			(net 600 "/Supply/1V8_FB")
			(pinfunction "FB")
			(pintype "input")
		)
	)
	(footprint "antmicro-footprints:DFN-10-1EP_3x3mm"
		(layer "F.Cu")
		(at 136.5 62.2 -90)
		(property "Reference" "U14"
			(at 1.808 1.88 270)
			(layer "F.SilkS")
			(effects
				(font
					(size 0.7 0.7)
					(thickness 0.15)
				)
				(justify left bottom)
			)
		)
		(property "Value" "MIC61300YML"
			(at 0 2.8 270)
			(layer "F.Fab")
			(effects
				(font
					(size 0.7 0.7)
					(thickness 0.15)
				)
				(justify left bottom)
			)
		)
		(property "Description" "Linear voltage regulator"
			(at 0 0 270)
			(layer "F.Fab")
			(hide yes)
			(effects
				(font
					(size 1.27 1.27)
					(thickness 0.15)
				)
			)
		)
		(property "Author" "Antmicro"
			(at 74.3 198.7 0)
			(layer "F.Fab")
			(hide yes)
			(effects
				(font
					(size 1 1)
					(thickness 0.15)
				)
			)
		)
		(property "License" "Apache-2.0"
			(at 74.3 198.7 0)
			(layer "F.Fab")
			(hide yes)
			(effects
				(font
					(size 1 1)
					(thickness 0.15)
				)
			)
		)
		(property "MPN" "MIC61300YML-TR"
			(at 74.3 198.7 0)
			(layer "F.Fab")
			(hide yes)
			(effects
				(font
					(size 1 1)
					(thickness 0.15)
				)
			)
		)
		(property "Manufacturer" "Microchip Technology"
			(at 74.3 198.7 0)
			(layer "F.Fab")
			(hide yes)
			(effects
				(font
					(size 1 1)
					(thickness 0.15)
				)
			)
		)
		(sheetname "Supply")
		(sheetfile "supply.kicad_sch")
		(attr smd)
		(fp_line
			(start -1.6 1.6)
			(end -1.35 1.6)
			(stroke
				(width 0.15)
				(type solid)
			)
			(layer "F.SilkS")
		)
		(fp_line
			(start -1.6 1.6)
			(end -1.6 1.35)
			(stroke
				(width 0.15)
				(type solid)
			)
			(layer "F.SilkS")
		)
		(fp_line
			(start 1.601 1.6)
			(end 1.401 1.6)
			(stroke
				(width 0.15)
				(type solid)
			)
			(layer "F.SilkS")
		)
		(fp_line
			(start 1.601 1.6)
			(end 1.601 1.35)
			(stroke
				(width 0.15)
				(type solid)
			)
			(layer "F.SilkS")
		)
		(fp_line
			(start -1.624 -1.226)
			(end -1.773 -1.226)
			(stroke
				(width 0.15)
				(type solid)
			)
			(layer "F.SilkS")
		)
		(fp_line
			(start -1.249 -1.601)
			(end -1.624 -1.226)
			(stroke
				(width 0.15)
				(type solid)
			)
			(layer "F.SilkS")
		)
		(fp_line
			(start -1.249 -1.601)
			(end -0.824 -1.601)
			(stroke
				(width 0.15)
				(type solid)
			)
			(layer "F.SilkS")
		)
		(fp_line
			(start 1.601 -1.601)
			(end 1.601 -1.401)
			(stroke
				(width 0.15)
				(type solid)
			)
			(layer "F.SilkS")
		)
		(fp_line
			(start 1.601 -1.601)
			(end 1.351 -1.601)
			(stroke
				(width 0.15)
				(type solid)
			)
			(layer "F.SilkS")
		)
		(fp_circle
			(center -1.8 -1.6)
			(end -1.8 -1.551)
			(stroke
				(width 0.15)
				(type solid)
			)
			(fill yes)
			(layer "F.SilkS")
		)
		(fp_line
			(start -1.91 1.75)
			(end -1.91 -1.73)
			(stroke
				(width 0.05)
				(type solid)
			)
			(layer "F.CrtYd")
		)
		(fp_line
			(start 1.89 1.75)
			(end -1.91 1.75)
			(stroke
				(width 0.05)
				(type solid)
			)
			(layer "F.CrtYd")
		)
		(fp_line
			(start 1.89 1.75)
			(end 1.89 -1.73)
			(stroke
				(width 0.05)
				(type solid)
			)
			(layer "F.CrtYd")
		)
		(fp_line
			(start -1.91 -1.73)
			(end 1.89 -1.73)
			(stroke
				(width 0.05)
				(type solid)
			)
			(layer "F.CrtYd")
		)
		(fp_line
			(start -1.499 1.499)
			(end -1.499 -1.176)
			(stroke
				(width 0.15)
				(type solid)
			)
			(layer "F.Fab")
		)
		(fp_line
			(start 1.5 1.499)
			(end -1.499 1.499)
			(stroke
				(width 0.15)
				(type solid)
			)
			(layer "F.Fab")
		)
		(fp_line
			(start -1.499 -1.18)
			(end -1.179 -1.5)
			(stroke
				(width 0.15)
				(type solid)
			)
			(layer "F.Fab")
		)
		(fp_line
			(start 1.5 -1.5)
			(end 1.5 1.499)
			(stroke
				(width 0.15)
				(type solid)
			)
			(layer "F.Fab")
		)
		(fp_line
			(start 1.5 -1.5)
			(end -1.175 -1.5)
			(stroke
				(width 0.15)
				(type solid)
			)
			(layer "F.Fab")
		)
		(pad "1" smd roundrect
			(at -1.425 -1 180)
			(size 0.25 0.7)
			(layers "F.Cu" "F.Mask" "F.Paste")
			(roundrect_rratio 0.25)
			(net 461 "1V1_SYS")
			(pinfunction "IN")
			(pintype "power_in")
		)
		(pad "2" smd roundrect
			(at -1.425 -0.5 180)
			(size 0.25 0.7)
			(layers "F.Cu" "F.Mask" "F.Paste")
			(roundrect_rratio 0.25)
			(net 461 "1V1_SYS")
			(pinfunction "IN")
			(pintype "passive")
		)
		(pad "3" smd roundrect
			(at -1.425 0 180)
			(size 0.25 0.7)
			(layers "F.Cu" "F.Mask" "F.Paste")
			(roundrect_rratio 0.25)
			(net 5 "GND")
			(pinfunction "GND")
			(pintype "passive")
		)
		(pad "4" smd roundrect
			(at -1.425 0.498 180)
			(size 0.25 0.7)
			(layers "F.Cu" "F.Mask" "F.Paste")
			(roundrect_rratio 0.25)
			(net 636 "/Supply/0V6_EN")
			(pinfunction "EN")
			(pintype "input")
		)
		(pad "5" smd roundrect
			(at -1.425 0.998 180)
			(size 0.25 0.7)
			(layers "F.Cu" "F.Mask" "F.Paste")
			(roundrect_rratio 0.25)
			(net 661 "unconnected-(U14-NC-Pad5)")
			(pinfunction "NC")
			(pintype "no_connect")
		)
		(pad "6" smd roundrect
			(at 1.426 0.998 180)
			(size 0.25 0.7)
			(layers "F.Cu" "F.Mask" "F.Paste")
			(roundrect_rratio 0.25)
			(net 662 "unconnected-(U14-NC-Pad6)")
			(pinfunction "NC")
			(pintype "no_connect")
		)
		(pad "7" smd roundrect
			(at 1.426 0.498 180)
			(size 0.25 0.7)
			(layers "F.Cu" "F.Mask" "F.Paste")
			(roundrect_rratio 0.25)
			(net 639 "/Supply/0V6_CP")
			(pinfunction "CP")
			(pintype "passive")
		)
		(pad "8" smd roundrect
			(at 1.426 0 180)
			(size 0.25 0.7)
			(layers "F.Cu" "F.Mask" "F.Paste")
			(roundrect_rratio 0.25)
			(net 635 "/Supply/0V6_FB")
			(pinfunction "FB")
			(pintype "input")
		)
		(pad "9" smd roundrect
			(at 1.426 -0.5 180)
			(size 0.25 0.7)
			(layers "F.Cu" "F.Mask" "F.Paste")
			(roundrect_rratio 0.25)
			(net 633 "/Supply/0V6_REG")
			(pinfunction "OUT")
			(pintype "passive")
		)
		(pad "10" smd roundrect
			(at 1.426 -1 180)
			(size 0.25 0.7)
			(layers "F.Cu" "F.Mask" "F.Paste")
			(roundrect_rratio 0.25)
			(net 633 "/Supply/0V6_REG")
			(pinfunction "OUT")
			(pintype "power_out")
		)
		(pad "11" smd roundrect
			(at 0 0 180)
			(size 2.38 1.65)
			(layers "F.Cu" "F.Mask" "F.Paste")
			(roundrect_rratio 0.05)
			(net 5 "GND")
			(pinfunction "GND")
			(pintype "passive")
		)
	)
	(footprint "antmicro-footprints:R_0402_1005Metric"
		(layer "F.Cu")
		(at 111.94 102.449)
		(descr "Resistor SMD 0402")
		(tags "resistor SMD 0402")
		(property "Reference" "R134"
			(at -3.64 0.351 0)
			(layer "F.SilkS")
			(effects
				(font
					(size 0.7 0.7)
					(thickness 0.15)
				)
				(justify left bottom)
			)
		)
		(property "Value" "R_31k6_0402"
			(at 0 1.4 0)
			(layer "F.Fab")
			(effects
				(font
					(size 0.7 0.7)
					(thickness 0.15)
				)
				(justify left bottom)
			)
		)
		(property "Description" "31k6 resistor in 0402 package with 1% tolerance"
			(at 0 0 0)
			(layer "F.Fab")
			(hide yes)
			(effects
				(font
					(size 1.27 1.27)
					(thickness 0.15)
				)
			)
		)
		(property "Author" "Antmicro"
			(at 0 0 0)
			(layer "F.Fab")
			(hide yes)
			(effects
				(font
					(size 1 1)
					(thickness 0.15)
				)
			)
		)
		(property "License" "Apache-2.0"
			(at 0 0 0)
			(layer "F.Fab")
			(hide yes)
			(effects
				(font
					(size 1 1)
					(thickness 0.15)
				)
			)
		)
		(property "MPN" "CR0402-FX-3162GLF"
			(at 0 0 0)
			(layer "F.Fab")
			(hide yes)
			(effects
				(font
					(size 1 1)
					(thickness 0.15)
				)
			)
		)
		(property "Manufacturer" "Bourns"
			(at 0 0 0)
			(layer "F.Fab")
			(hide yes)
			(effects
				(font
					(size 1 1)
					(thickness 0.15)
				)
			)
		)
		(property "Tolerance" "1%"
			(at 0 0 0)
			(layer "F.Fab")
			(hide yes)
			(effects
				(font
					(size 1 1)
					(thickness 0.15)
				)
			)
		)
		(property "Val" "31k6"
			(at 0 0 0)
			(layer "F.Fab")
			(hide yes)
			(effects
				(font
					(size 1 1)
					(thickness 0.15)
				)
			)
		)
		(sheetname "Supply")
		(sheetfile "supply.kicad_sch")
		(attr smd)
		(fp_rect
			(start -0.93 -0.47)
			(end 0.93 0.47)
			(stroke
				(width 0.05)
				(type solid)
			)
			(fill no)
			(layer "F.CrtYd")
		)
		(fp_rect
			(start -0.5 -0.25)
			(end 0.5 0.25)
			(stroke
				(width 0.15)
				(type solid)
			)
			(fill no)
			(layer "F.Fab")
		)
		(pad "1" smd roundrect
			(at -0.485 0)
			(size 0.59 0.64)
			(layers "F.Cu" "F.Mask" "F.Paste")
			(roundrect_rratio 0.25)
			(net 576 "/Supply/3V3_REG")
			(pintype "passive")
		)
		(pad "2" smd roundrect
			(at 0.485 0)
			(size 0.59 0.64)
			(layers "F.Cu" "F.Mask" "F.Paste")
			(roundrect_rratio 0.25)
			(net 578 "/Supply/3V3_FB")
			(pintype "passive")
		)
	)
	(footprint "antmicro-footprints:R_0402_1005Metric"
		(layer "F.Cu")
		(at 123.65 89.974 180)
		(descr "Resistor SMD 0402")
		(tags "resistor SMD 0402")
		(property "Reference" "R139"
			(at 3.65 -0.326 180)
			(layer "F.SilkS")
			(effects
				(font
					(size 0.7 0.7)
					(thickness 0.15)
				)
				(justify left bottom)
			)
		)
		(property "Value" "R_10k_0402"
			(at 0 1.4 180)
			(layer "F.Fab")
			(effects
				(font
					(size 0.7 0.7)
					(thickness 0.15)
				)
				(justify left bottom)
			)
		)
		(property "Description" "10k resistor in 0402 package with 1% tolerance"
			(at 0 0 180)
			(layer "F.Fab")
			(hide yes)
			(effects
				(font
					(size 1.27 1.27)
					(thickness 0.15)
				)
			)
		)
		(property "Author" "Antmicro"
			(at 247.3 179.948 0)
			(layer "F.Fab")
			(hide yes)
			(effects
				(font
					(size 1 1)
					(thickness 0.15)
				)
			)
		)
		(property "License" "Apache-2.0"
			(at 247.3 179.948 0)
			(layer "F.Fab")
			(hide yes)
			(effects
				(font
					(size 1 1)
					(thickness 0.15)
				)
			)
		)
		(property "MPN" "CR0402-FX-1002GLF"
			(at 247.3 179.948 0)
			(layer "F.Fab")
			(hide yes)
			(effects
				(font
					(size 1 1)
					(thickness 0.15)
				)
			)
		)
		(property "Manufacturer" "Bourns"
			(at 247.3 179.948 0)
			(layer "F.Fab")
			(hide yes)
			(effects
				(font
					(size 1 1)
					(thickness 0.15)
				)
			)
		)
		(property "Tolerance" "1%"
			(at 247.3 179.948 0)
			(layer "F.Fab")
			(hide yes)
			(effects
				(font
					(size 1 1)
					(thickness 0.15)
				)
			)
		)
		(property "Val" "10k"
			(at 247.3 179.948 0)
			(layer "F.Fab")
			(hide yes)
			(effects
				(font
					(size 1 1)
					(thickness 0.15)
				)
			)
		)
		(sheetname "Supply")
		(sheetfile "supply.kicad_sch")
		(attr smd)
		(fp_rect
			(start -0.93 -0.47)
			(end 0.93 0.47)
			(stroke
				(width 0.05)
				(type solid)
			)
			(fill no)
			(layer "F.CrtYd")
		)
		(fp_rect
			(start -0.5 -0.25)
			(end 0.5 0.25)
			(stroke
				(width 0.15)
				(type solid)
			)
			(fill no)
			(layer "F.Fab")
		)
		(pad "1" smd roundrect
			(at -0.485 0 180)
			(size 0.59 0.64)
			(layers "F.Cu" "F.Mask" "F.Paste")
			(roundrect_rratio 0.25)
			(net 598 "/Supply/1V1_FB")
			(pintype "passive")
		)
		(pad "2" smd roundrect
			(at 0.485 0 180)
			(size 0.59 0.64)
			(layers "F.Cu" "F.Mask" "F.Paste")
			(roundrect_rratio 0.25)
			(net 5 "GND")
			(pintype "passive")
		)
	)
	(footprint "antmicro-footprints:R_0402_1005Metric"
		(layer "F.Cu")
		(at 185 118.185 90)
		(descr "Resistor SMD 0402")
		(tags "resistor SMD 0402")
		(property "Reference" "R126"
			(at -3.615 0.436828 90)
			(layer "F.SilkS")
			(effects
				(font
					(size 0.7 0.7)
					(thickness 0.15)
				)
				(justify left bottom)
			)
		)
		(property "Value" "R_100k_0402"
			(at 0 1.4 90)
			(layer "F.Fab")
			(effects
				(font
					(size 0.7 0.7)
					(thickness 0.15)
				)
				(justify left bottom)
			)
		)
		(property "Description" "100k resistor in 0402 package with 1% tolerance"
			(at 0 0 90)
			(layer "F.Fab")
			(hide yes)
			(effects
				(font
					(size 1.27 1.27)
					(thickness 0.15)
				)
			)
		)
		(property "Author" "Antmicro"
			(at 303.185 -66.815 0)
			(layer "F.Fab")
			(hide yes)
			(effects
				(font
					(size 1 1)
					(thickness 0.15)
				)
			)
		)
		(property "License" "Apache-2.0"
			(at 303.185 -66.815 0)
			(layer "F.Fab")
			(hide yes)
			(effects
				(font
					(size 1 1)
					(thickness 0.15)
				)
			)
		)
		(property "MPN" "CR0402-FX-1003GLF"
			(at 303.185 -66.815 0)
			(layer "F.Fab")
			(hide yes)
			(effects
				(font
					(size 1 1)
					(thickness 0.15)
				)
			)
		)
		(property "Manufacturer" "Bourns"
			(at 303.185 -66.815 0)
			(layer "F.Fab")
			(hide yes)
			(effects
				(font
					(size 1 1)
					(thickness 0.15)
				)
			)
		)
		(property "Tolerance" "1%"
			(at 303.185 -66.815 0)
			(layer "F.Fab")
			(hide yes)
			(effects
				(font
					(size 1 1)
					(thickness 0.15)
				)
			)
		)
		(property "Val" "100k"
			(at 303.185 -66.815 0)
			(layer "F.Fab")
			(hide yes)
			(effects
				(font
					(size 1 1)
					(thickness 0.15)
				)
			)
		)
		(sheetname "Supply")
		(sheetfile "supply.kicad_sch")
		(attr smd)
		(fp_rect
			(start -0.93 -0.47)
			(end 0.93 0.47)
			(stroke
				(width 0.05)
				(type solid)
			)
			(fill no)
			(layer "F.CrtYd")
		)
		(fp_rect
			(start -0.5 -0.25)
			(end 0.5 0.25)
			(stroke
				(width 0.15)
				(type solid)
			)
			(fill no)
			(layer "F.Fab")
		)
		(pad "1" smd roundrect
			(at -0.485 0 90)
			(size 0.59 0.64)
			(layers "F.Cu" "F.Mask" "F.Paste")
			(roundrect_rratio 0.25)
			(net 470 "/Supply/VCC_IO_EN")
			(pintype "passive")
		)
		(pad "2" smd roundrect
			(at 0.485 0 90)
			(size 0.59 0.64)
			(layers "F.Cu" "F.Mask" "F.Paste")
			(roundrect_rratio 0.25)
			(net 596 "/Supply/1V2_EN")
			(pintype "passive")
		)
	)
)
